# S9S_MB_2U (Grand Teton) — schematic netlist excerpt (pin names and nets, part order shuffled) for the footprints in the layout excerpt that follows; sources: Cadence DE-HDL packaged netlist, KiCad conversion of 03242023_DA0F0TMBIJ0_F0T_Motherboard_J_brd_V01_OCP.brd

R3873  Q_RES  0 5% EMPTY  pkg 0402LF  page 163 : A = P12V_OCP_IMON_2 ; B = P12V_OCP_V3_2_ISENSE_MPS_MAM
C838  Q_CAP_DIFFBUS  DIFF BUS_0.22UF 6.3V 20% X6S  pkg C0201  page 174 : \1\ = P5E_CPU0_PE1_TX_C_DN<15> ; \2\ = P5E_CPU0_PE1_TX_DN<15>
C1541  Q_CAP_DIFFBUS  DIFF BUS_0.22UF 6.3V 20% X6S  pkg C0201  page 177 : \1\ = P5E_CPU1_PE3_TX_C_DP<3> ; \2\ = P5E_CPU1_PE3_TX_DP<3>

(kicad_pcb
	(version 20260206)
	(generator "pcbnew")
	(generator_version "10.0")
	(general
		(thickness 1.6)
		(legacy_teardrops no)
	)
	(paper "A4")
	(title_block
		(title "03242023_DA0F0TMBIJ0_F0T_Motherboard_J_brd_V01_OCP.brd")
		(comment 1 "Grand Teton / footprints 2452-2454 of 6105")
	)
	(layers
		(0 "F.Cu" signal "TOP")
		(4 "In1.Cu" signal "GND")
		(6 "In2.Cu" signal "IN1")
		(8 "In3.Cu" signal "GND1")
		(10 "In4.Cu" signal "IN2")
		(12 "In5.Cu" signal "GND2")
		(14 "In6.Cu" signal "IN3")
		(16 "In7.Cu" signal "GND3")
		(18 "In8.Cu" signal "VCC")
		(20 "In9.Cu" signal "VCC1")
		(22 "In10.Cu" signal "GND4")
		(24 "In11.Cu" signal "IN4")
		(26 "In12.Cu" signal "GND5")
		(28 "In13.Cu" signal "IN5")
		(30 "In14.Cu" signal "GND6")
		(32 "In15.Cu" signal "IN6")
		(34 "In16.Cu" signal "GND7")
		(2 "B.Cu" signal "BOTTOM")
		(9 "F.Adhes" user "F.Adhesive")
		(11 "B.Adhes" user "B.Adhesive")
		(13 "F.Paste" user "Package Geometry/Pastemask Top")
		(15 "B.Paste" user "Package Geometry/Pastemask Bottom")
		(5 "F.SilkS" user "Ref Des/Silkscreen Top")
		(7 "B.SilkS" user "Ref Des/Silkscreen Bottom")
		(1 "F.Mask" user "Board Geometry/Soldermask Top")
		(3 "B.Mask" user "Board Geometry/Soldermask Bottom")
		(17 "Dwgs.User" user "User.Drawings")
		(19 "Cmts.User" user "User.Comments")
		(21 "Eco1.User" user "User.Eco1")
		(23 "Eco2.User" user "User.Eco2")
		(25 "Edge.Cuts" user "Board Geometry/Outline")
		(27 "Margin" user)
		(31 "F.CrtYd" user "Package Geometry/Place Bound Top")
		(29 "B.CrtYd" user "Package Geometry/Place Bound Bottom")
		(35 "F.Fab" user "Ref Des/Assembly Top")
		(33 "B.Fab" user "Ref Des/Assembly Bottom")
	)
	(footprint ""
		(layer "F.Cu")
		(at 390.930384 -16.088614 90)
		(property "Reference" "C838"
			(at 0 0 90)
			(layer "F.SilkS")
			(hide yes)
			(effects
				(font
					(size 1.27 1.27)
				)
			)
		)
		(property "Value" ""
			(at 0 0 90)
			(layer "F.Fab")
			(effects
				(font
					(size 1.27 1.27)
				)
			)
		)
		(duplicate_pad_numbers_are_jumpers no)
		(fp_line
			(start 0.299974 -0.150114)
			(end 0.299974 0.150114)
			(stroke
				(width 0.1)
				(type default)
			)
			(layer "F.Fab")
		)
		(fp_line
			(start -0.299974 -0.150114)
			(end 0.299974 -0.150114)
			(stroke
				(width 0.1)
				(type default)
			)
			(layer "F.Fab")
		)
		(fp_line
			(start 0.299974 0.150114)
			(end -0.299974 0.150114)
			(stroke
				(width 0.1)
				(type default)
			)
			(layer "F.Fab")
		)
		(fp_line
			(start -0.299974 0.150114)
			(end -0.299974 -0.150114)
			(stroke
				(width 0.1)
				(type default)
			)
			(layer "F.Fab")
		)
		(pad "1" smd rect
			(at -0.2667 0 90)
			(size 0.3048 0.381)
			(layers "F.Cu" "F.Mask" "F.Paste")
			(net "P5E_CPU0_PE1_TX_C_DN<15>")
		)
		(pad "2" smd rect
			(at 0.2667 0 90)
			(size 0.3048 0.381)
			(layers "F.Cu" "F.Mask" "F.Paste")
			(net "P5E_CPU0_PE1_TX_DN<15>")
		)
	)
	(footprint ""
		(layer "F.Cu")
		(at 159.149034 -408.517344 -90)
		(property "Reference" "C1541"
			(at 0 0 270)
			(layer "F.SilkS")
			(hide yes)
			(effects
				(font
					(size 1.27 1.27)
				)
			)
		)
		(property "Value" ""
			(at 0 0 270)
			(layer "F.Fab")
			(effects
				(font
					(size 1.27 1.27)
				)
			)
		)
		(duplicate_pad_numbers_are_jumpers no)
		(fp_line
			(start -0.299974 0.150114)
			(end -0.299974 -0.150114)
			(stroke
				(width 0.1)
				(type default)
			)
			(layer "F.Fab")
		)
		(fp_line
			(start 0.299974 0.150114)
			(end -0.299974 0.150114)
			(stroke
				(width 0.1)
				(type default)
			)
			(layer "F.Fab")
		)
		(fp_line
			(start -0.299974 -0.150114)
			(end 0.299974 -0.150114)
			(stroke
				(width 0.1)
				(type default)
			)
			(layer "F.Fab")
		)
		(fp_line
			(start 0.299974 -0.150114)
			(end 0.299974 0.150114)
			(stroke
				(width 0.1)
				(type default)
			)
			(layer "F.Fab")
		)
		(pad "1" smd rect
			(at -0.2667 0 270)
			(size 0.3048 0.381)
			(layers "F.Cu" "F.Mask" "F.Paste")
			(net "P5E_CPU1_PE3_TX_C_DP<3>")
		)
		(pad "2" smd rect
			(at 0.2667 0 270)
			(size 0.3048 0.381)
			(layers "F.Cu" "F.Mask" "F.Paste")
			(net "P5E_CPU1_PE3_TX_DP<3>")
		)
	)
	(footprint ""
		(layer "F.Cu")
		(at 62.559438 -31.887922 90)
		(property "Reference" "R3873"
			(at 0 0 90)
			(layer "F.SilkS")
			(hide yes)
			(effects
				(font
					(size 1.27 1.27)
				)
			)
		)
		(property "Value" ""
			(at 0 0 90)
			(layer "F.Fab")
			(effects
				(font
					(size 1.27 1.27)
				)
			)
		)
		(duplicate_pad_numbers_are_jumpers no)
		(fp_line
			(start 0.7874 -0.4064)
			(end 0.7874 0.4064)
			(stroke
				(width 0.1524)
				(type default)
			)
			(layer "F.SilkS")
		)
		(fp_line
			(start -0.7874 -0.4064)
			(end 0.7874 -0.4064)
			(stroke
				(width 0.1524)
				(type default)
			)
			(layer "F.SilkS")
		)
		(fp_line
			(start 0.7874 0.4064)
			(end -0.7874 0.4064)
			(stroke
				(width 0.1524)
				(type default)
			)
			(layer "F.SilkS")
		)
		(fp_line
			(start -0.7874 0.4064)
			(end -0.7874 -0.4064)
			(stroke
				(width 0.1524)
				(type default)
			)
			(layer "F.SilkS")
		)
		(fp_line
			(start -0.12065 -0.305054)
			(end -0.12065 -0.2794)
			(stroke
				(width 0.1)
				(type default)
			)
			(layer "F.Fab")
		)
		(fp_line
			(start -0.67945 -0.305054)
			(end -0.12065 -0.305054)
			(stroke
				(width 0.1)
				(type default)
			)
			(layer "F.Fab")
		)
		(fp_line
			(start 0.67945 -0.3048)
			(end 0.67945 0.3048)
			(stroke
				(width 0.1)
				(type default)
			)
			(layer "F.Fab")
		)
		(fp_line
			(start 0.12065 -0.3048)
			(end 0.67945 -0.3048)
			(stroke
				(width 0.1)
				(type default)
			)
			(layer "F.Fab")
		)
		(fp_line
			(start 0.12065 -0.2794)
			(end 0.12065 -0.3048)
			(stroke
				(width 0.1)
				(type default)
			)
			(layer "F.Fab")
		)
		(fp_line
			(start -0.12065 -0.2794)
			(end 0.12065 -0.2794)
			(stroke
				(width 0.1)
				(type default)
			)
			(layer "F.Fab")
		)
		(fp_line
			(start 0.120396 0.2794)
			(end -0.12065 0.2794)
			(stroke
				(width 0.1)
				(type default)
			)
			(layer "F.Fab")
		)
		(fp_line
			(start -0.12065 0.2794)
			(end -0.12065 0.3048)
			(stroke
				(width 0.1)
				(type default)
			)
			(layer "F.Fab")
		)
		(fp_line
			(start 0.67945 0.3048)
			(end 0.120396 0.3048)
			(stroke
				(width 0.1)
				(type default)
			)
			(layer "F.Fab")
		)
		(fp_line
			(start 0.120396 0.3048)
			(end 0.120396 0.2794)
			(stroke
				(width 0.1)
				(type default)
			)
			(layer "F.Fab")
		)
		(fp_line
			(start -0.12065 0.3048)
			(end -0.67945 0.3048)
			(stroke
				(width 0.1)
				(type default)
			)
			(layer "F.Fab")
		)
		(fp_line
			(start -0.67945 0.3048)
			(end -0.67945 -0.305054)
			(stroke
				(width 0.1)
				(type default)
			)
			(layer "F.Fab")
		)
		(pad "1" smd circle
			(at -0.40005 0 90)
			(size 0 0)
			(layers "F.Cu" "F.Mask" "F.Paste")
			(net "P12V_OCP_IMON_2")
		)
		(pad "2" smd circle
			(at 0.40005 0 90)
			(size 0 0)
			(layers "F.Cu" "F.Mask" "F.Paste")
			(net "P12V_OCP_V3_2_ISENSE_MPS_MAM")
		)
	)
)
